# BASEBOARD_FAB2 (Tioga Pass) — schematic netlist excerpt (pin names and nets, part order shuffled) for the footprints in the layout excerpt that follows; sources: Cadence DE-HDL packaged netlist, KiCad conversion of Wiwynn_Tioga_Pass_MB.brd

C3M13  CAP  0.22UF 16V 10% X7R  pkg 0402  page 105 : A = P3E_CPU0_PE1_PCH_R_RXP<13> ; B = P3E_CPU0_PE1_PCH_RXP<13>
C3L15  CAP  10UF 16V 10% X6S  pkg 0805  page 219 : A = VR_FET_SW_P12V_STBY_PVDDQ_DEF ; B = GND
R1U59  RES  0.0 5% CHIP  pkg 0402  page 152 : A = H_CPU0_ABC_MEMHOT_LVT3_R_N ; B = H_CPU0_MEMABC_MEMHOT_LVT3_K_N

(kicad_pcb
	(version 20260206)
	(generator "pcbnew")
	(generator_version "10.0")
	(general
		(thickness 1.6)
		(legacy_teardrops no)
	)
	(paper "A4")
	(title_block
		(title "Wiwynn_Tioga_Pass_MB.brd")
		(comment 1 "Tioga Pass / footprints 3768-3770 of 4770")
	)
	(layers
		(0 "F.Cu" signal "TOP")
		(4 "In1.Cu" signal "L2GND")
		(6 "In2.Cu" signal "L3")
		(8 "In3.Cu" signal "L4GND")
		(10 "In4.Cu" signal "L5")
		(12 "In5.Cu" signal "L6GND")
		(14 "In6.Cu" signal "L7VCC")
		(16 "In7.Cu" signal "L8VCC")
		(18 "In8.Cu" signal "L9GND")
		(20 "In9.Cu" signal "L10")
		(22 "In10.Cu" signal "L11GND")
		(24 "In11.Cu" signal "L12")
		(26 "In12.Cu" signal "L13GND")
		(2 "B.Cu" signal "BOTTOM")
		(9 "F.Adhes" user "F.Adhesive")
		(11 "B.Adhes" user "B.Adhesive")
		(13 "F.Paste" user "Package Geometry/Pastemask Top")
		(15 "B.Paste" user "Package Geometry/Pastemask Bottom")
		(5 "F.SilkS" user "Ref Des/Silkscreen Top")
		(7 "B.SilkS" user "Ref Des/Silkscreen Bottom")
		(1 "F.Mask" user "Board Geometry/Soldermask Top")
		(3 "B.Mask" user "Board Geometry/Soldermask Bottom")
		(17 "Dwgs.User" user "User.Drawings")
		(19 "Cmts.User" user "User.Comments")
		(21 "Eco1.User" user "User.Eco1")
		(23 "Eco2.User" user "User.Eco2")
		(25 "Edge.Cuts" user "Board Geometry/Outline")
		(27 "Margin" user)
		(31 "F.CrtYd" user "Package Geometry/Place Bound Top")
		(29 "B.CrtYd" user "Package Geometry/Place Bound Bottom")
		(35 "F.Fab" user "Ref Des/Assembly Top")
		(33 "B.Fab" user "Ref Des/Assembly Bottom")
	)
	(footprint ""
		(layer "B.Cu")
		(at 349.463614 -123.576842 -90)
		(property "Reference" "C3M13"
			(at 0 0 90)
			(layer "B.SilkS")
			(hide yes)
			(effects
				(font
					(size 1.27 1.27)
				)
				(justify mirror)
			)
		)
		(property "Value" ""
			(at 0 0 90)
			(layer "B.Fab")
			(effects
				(font
					(size 1.27 1.27)
				)
				(justify mirror)
			)
		)
		(duplicate_pad_numbers_are_jumpers no)
		(fp_poly
			(pts
				(xy -0.3048 -0.1016) (xy -0.3048 0.9906) (xy 0.3048 0.9906) (xy 0.3048 -0.1016)
			)
			(stroke
				(width 0)
				(type default)
			)
			(fill no)
			(layer "B.CrtYd")
		)
		(fp_line
			(start -0.3048 0.9906)
			(end -0.3048 -0.1016)
			(stroke
				(width 0.1)
				(type default)
			)
			(layer "B.Fab")
		)
		(fp_line
			(start 0.3048 0.9906)
			(end -0.3048 0.9906)
			(stroke
				(width 0.1)
				(type default)
			)
			(layer "B.Fab")
		)
		(fp_line
			(start -0.3048 -0.1016)
			(end 0.3048 -0.1016)
			(stroke
				(width 0.1)
				(type default)
			)
			(layer "B.Fab")
		)
		(fp_line
			(start 0.3048 -0.1016)
			(end 0.3048 0.9906)
			(stroke
				(width 0.1)
				(type default)
			)
			(layer "B.Fab")
		)
		(pad "1" smd rect
			(at 0 0 90)
			(size 0.508 0.508)
			(layers "B.Cu" "B.Mask" "B.Paste")
			(net "P3E_CPU0_PE1_PCH_R_RXP<13>")
		)
		(pad "2" smd rect
			(at 0 0.889 90)
			(size 0.508 0.508)
			(layers "B.Cu" "B.Mask" "B.Paste")
			(net "P3E_CPU0_PE1_PCH_RXP<13>")
		)
		(zone
			(layer "B.Cu")
			(hatch none 0.5)
			(connect_pads
				(clearance 0)
			)
			(min_thickness 0.25)
			(keepout
				(tracks not_allowed)
				(vias allowed)
				(pads allowed)
				(copperpour not_allowed)
				(footprints allowed)
			)
			(placement
				(enabled no)
				(sheetname "")
			)
			(fill
				(thermal_gap 0.5)
				(thermal_bridge_width 0.5)
				(island_removal_mode 0)
			)
			(polygon
				(pts
					(xy 348.828614 -123.322842) (xy 348.828614 -123.830842) (xy 349.209614 -123.830842) (xy 349.209614 -123.322842)
				)
			)
		)
		(zone
			(layer "B.Cu")
			(hatch none 0.5)
			(connect_pads
				(clearance 0)
			)
			(min_thickness 0.25)
			(keepout
				(tracks allowed)
				(vias not_allowed)
				(pads allowed)
				(copperpour not_allowed)
				(footprints allowed)
			)
			(placement
				(enabled no)
				(sheetname "")
			)
			(fill
				(thermal_gap 0.5)
				(thermal_bridge_width 0.5)
				(island_removal_mode 0)
			)
			(polygon
				(pts
					(xy 349.209614 -123.322842) (xy 349.209614 -123.830842) (xy 348.828614 -123.830842) (xy 348.828614 -123.322842)
				)
			)
		)
	)
	(footprint ""
		(layer "B.Cu")
		(at 348.5134 -152.038304 -90)
		(property "Reference" "C3L15"
			(at 0 0 90)
			(layer "B.SilkS")
			(hide yes)
			(effects
				(font
					(size 1.27 1.27)
				)
				(justify mirror)
			)
		)
		(property "Value" ""
			(at 0 0 90)
			(layer "B.Fab")
			(effects
				(font
					(size 1.27 1.27)
				)
				(justify mirror)
			)
		)
		(duplicate_pad_numbers_are_jumpers no)
		(fp_poly
			(pts
				(xy 0.7239 -0.2159) (xy -0.7239 -0.2159) (xy -0.7239 1.9939) (xy 0.7239 1.9939)
			)
			(stroke
				(width 0)
				(type default)
			)
			(fill no)
			(layer "B.CrtYd")
		)
		(fp_line
			(start -0.7239 1.9939)
			(end -0.7239 -0.2159)
			(stroke
				(width 0.1)
				(type default)
			)
			(layer "B.Fab")
		)
		(fp_line
			(start 0.7239 1.9939)
			(end -0.7239 1.9939)
			(stroke
				(width 0.1)
				(type default)
			)
			(layer "B.Fab")
		)
		(fp_line
			(start -0.7239 -0.2159)
			(end 0.7239 -0.2159)
			(stroke
				(width 0.1)
				(type default)
			)
			(layer "B.Fab")
		)
		(fp_line
			(start 0.7239 -0.2159)
			(end 0.7239 1.9939)
			(stroke
				(width 0.1)
				(type default)
			)
			(layer "B.Fab")
		)
		(pad "1" smd rect
			(at 0 0 90)
			(size 1.27 1.016)
			(layers "B.Cu" "B.Mask" "B.Paste")
			(net "VR_FET_SW_P12V_STBY_PVDDQ_DEF")
		)
		(pad "2" smd rect
			(at 0 1.778 90)
			(size 1.27 1.016)
			(layers "B.Cu" "B.Mask" "B.Paste")
			(net "GND")
		)
		(zone
			(layer "B.Cu")
			(hatch none 0.5)
			(connect_pads
				(clearance 0)
			)
			(min_thickness 0.25)
			(keepout
				(tracks not_allowed)
				(vias allowed)
				(pads allowed)
				(copperpour not_allowed)
				(footprints allowed)
			)
			(placement
				(enabled no)
				(sheetname "")
			)
			(fill
				(thermal_gap 0.5)
				(thermal_bridge_width 0.5)
				(island_removal_mode 0)
			)
			(polygon
				(pts
					(xy 348.0054 -151.403304) (xy 348.0054 -152.673304) (xy 347.2434 -152.673304) (xy 347.2434 -151.403304)
				)
			)
		)
	)
	(footprint ""
		(layer "B.Cu")
		(at 430.2125 -12.446 -90)
		(property "Reference" "R1U59"
			(at 0 0 90)
			(layer "B.SilkS")
			(hide yes)
			(effects
				(font
					(size 1.27 1.27)
				)
				(justify mirror)
			)
		)
		(property "Value" ""
			(at 0 0 90)
			(layer "B.Fab")
			(effects
				(font
					(size 1.27 1.27)
				)
				(justify mirror)
			)
		)
		(duplicate_pad_numbers_are_jumpers no)
		(fp_poly
			(pts
				(xy 0.2794 -0.1016) (xy -0.2794 -0.1016) (xy -0.2794 0.9906) (xy 0.2794 0.9906)
			)
			(stroke
				(width 0)
				(type default)
			)
			(fill no)
			(layer "B.CrtYd")
		)
		(fp_line
			(start -0.2794 0.9906)
			(end -0.2794 -0.1016)
			(stroke
				(width 0.1)
				(type default)
			)
			(layer "B.Fab")
		)
		(fp_line
			(start 0.2794 0.9906)
			(end -0.2794 0.9906)
			(stroke
				(width 0.1)
				(type default)
			)
			(layer "B.Fab")
		)
		(fp_line
			(start -0.2794 -0.1016)
			(end 0.2794 -0.1016)
			(stroke
				(width 0.1)
				(type default)
			)
			(layer "B.Fab")
		)
		(fp_line
			(start 0.2794 -0.1016)
			(end 0.2794 0.9906)
			(stroke
				(width 0.1)
				(type default)
			)
			(layer "B.Fab")
		)
		(pad "1" smd rect
			(at 0 0 90)
			(size 0.508 0.508)
			(layers "B.Cu" "B.Mask" "B.Paste")
			(net "H_CPU0_ABC_MEMHOT_LVT3_R_N")
		)
		(pad "2" smd rect
			(at 0 0.889 90)
			(size 0.508 0.508)
			(layers "B.Cu" "B.Mask" "B.Paste")
			(net "H_CPU0_MEMABC_MEMHOT_LVT3_K_N")
		)
		(zone
			(layer "B.Cu")
			(hatch none 0.5)
			(connect_pads
				(clearance 0)
			)
			(min_thickness 0.25)
			(keepout
				(tracks not_allowed)
				(vias allowed)
				(pads allowed)
				(copperpour not_allowed)
				(footprints allowed)
			)
			(placement
				(enabled no)
				(sheetname "")
			)
			(fill
				(thermal_gap 0.5)
				(thermal_bridge_width 0.5)
				(island_removal_mode 0)
			)
			(polygon
				(pts
					(xy 429.5775 -12.192) (xy 429.5775 -12.7) (xy 429.9585 -12.7) (xy 429.9585 -12.192)
				)
			)
		)
		(zone
			(layer "B.Cu")
			(hatch none 0.5)
			(connect_pads
				(clearance 0)
			)
			(min_thickness 0.25)
			(keepout
				(tracks allowed)
				(vias not_allowed)
				(pads allowed)
				(copperpour not_allowed)
				(footprints allowed)
			)
			(placement
				(enabled no)
				(sheetname "")
			)
			(fill
				(thermal_gap 0.5)
				(thermal_bridge_width 0.5)
				(island_removal_mode 0)
			)
			(polygon
				(pts
					(xy 429.9585 -12.192) (xy 429.9585 -12.7) (xy 429.5775 -12.7) (xy 429.5775 -12.192)
				)
			)
		)
	)
)
